# S9S_MB_2U (Grand Teton) — schematic netlist excerpt (pin names and nets, part order shuffled) for the footprints in the layout excerpt that follows; sources: Cadence DE-HDL packaged netlist, KiCad conversion of 03242023_DA0F0TMBIJ0_F0T_Motherboard_J_brd_V01_OCP.brd

R4048  Q_RES  33.2 1% CHIP  pkg 0402LF  page 225 : A = RST_CPU1_DRAM_EF_PLD_LVT3_R_N ; B = RST_CPU1_DRAM_EF_PLD_LVT3_N
R540  Q_RES  10K 1% EMPTY  pkg 0402LF  page 231 : A = P3V3_AUX ; B = PCA9548_PCIE3_ADDR0

(kicad_pcb
	(version 20260206)
	(generator "pcbnew")
	(generator_version "10.0")
	(general
		(thickness 1.6)
		(legacy_teardrops no)
	)
	(paper "A4")
	(title_block
		(title "03242023_DA0F0TMBIJ0_F0T_Motherboard_J_brd_V01_OCP.brd")
		(comment 1 "Grand Teton / footprints 3771-3772 of 6105")
	)
	(layers
		(0 "F.Cu" signal "TOP")
		(4 "In1.Cu" signal "GND")
		(6 "In2.Cu" signal "IN1")
		(8 "In3.Cu" signal "GND1")
		(10 "In4.Cu" signal "IN2")
		(12 "In5.Cu" signal "GND2")
		(14 "In6.Cu" signal "IN3")
		(16 "In7.Cu" signal "GND3")
		(18 "In8.Cu" signal "VCC")
		(20 "In9.Cu" signal "VCC1")
		(22 "In10.Cu" signal "GND4")
		(24 "In11.Cu" signal "IN4")
		(26 "In12.Cu" signal "GND5")
		(28 "In13.Cu" signal "IN5")
		(30 "In14.Cu" signal "GND6")
		(32 "In15.Cu" signal "IN6")
		(34 "In16.Cu" signal "GND7")
		(2 "B.Cu" signal "BOTTOM")
		(9 "F.Adhes" user "F.Adhesive")
		(11 "B.Adhes" user "B.Adhesive")
		(13 "F.Paste" user "Package Geometry/Pastemask Top")
		(15 "B.Paste" user "Package Geometry/Pastemask Bottom")
		(5 "F.SilkS" user "Ref Des/Silkscreen Top")
		(7 "B.SilkS" user "Ref Des/Silkscreen Bottom")
		(1 "F.Mask" user "Board Geometry/Soldermask Top")
		(3 "B.Mask" user "Board Geometry/Soldermask Bottom")
		(17 "Dwgs.User" user "User.Drawings")
		(19 "Cmts.User" user "User.Comments")
		(21 "Eco1.User" user "User.Eco1")
		(23 "Eco2.User" user "User.Eco2")
		(25 "Edge.Cuts" user "Board Geometry/Outline")
		(27 "Margin" user)
		(31 "F.CrtYd" user "Package Geometry/Place Bound Top")
		(29 "B.CrtYd" user "Package Geometry/Place Bound Bottom")
		(35 "F.Fab" user "Ref Des/Assembly Top")
		(33 "B.Fab" user "Ref Des/Assembly Bottom")
	)
	(footprint ""
		(layer "F.Cu")
		(at 111.332772 -140.403326)
		(property "Reference" "R540"
			(at 0 0 0)
			(layer "F.SilkS")
			(hide yes)
			(effects
				(font
					(size 1.27 1.27)
				)
			)
		)
		(property "Value" ""
			(at 0 0 0)
			(layer "F.Fab")
			(effects
				(font
					(size 1.27 1.27)
				)
			)
		)
		(duplicate_pad_numbers_are_jumpers no)
		(fp_line
			(start -0.7874 -0.4064)
			(end 0.7874 -0.4064)
			(stroke
				(width 0.1524)
				(type default)
			)
			(layer "F.SilkS")
		)
		(fp_line
			(start -0.7874 0.4064)
			(end -0.7874 -0.4064)
			(stroke
				(width 0.1524)
				(type default)
			)
			(layer "F.SilkS")
		)
		(fp_line
			(start 0.7874 -0.4064)
			(end 0.7874 0.4064)
			(stroke
				(width 0.1524)
				(type default)
			)
			(layer "F.SilkS")
		)
		(fp_line
			(start 0.7874 0.4064)
			(end -0.7874 0.4064)
			(stroke
				(width 0.1524)
				(type default)
			)
			(layer "F.SilkS")
		)
		(fp_line
			(start -0.67945 -0.305054)
			(end -0.12065 -0.305054)
			(stroke
				(width 0.1)
				(type default)
			)
			(layer "F.Fab")
		)
		(fp_line
			(start -0.67945 0.3048)
			(end -0.67945 -0.305054)
			(stroke
				(width 0.1)
				(type default)
			)
			(layer "F.Fab")
		)
		(fp_line
			(start -0.12065 -0.305054)
			(end -0.12065 -0.2794)
			(stroke
				(width 0.1)
				(type default)
			)
			(layer "F.Fab")
		)
		(fp_line
			(start -0.12065 -0.2794)
			(end 0.12065 -0.2794)
			(stroke
				(width 0.1)
				(type default)
			)
			(layer "F.Fab")
		)
		(fp_line
			(start -0.12065 0.2794)
			(end -0.12065 0.3048)
			(stroke
				(width 0.1)
				(type default)
			)
			(layer "F.Fab")
		)
		(fp_line
			(start -0.12065 0.3048)
			(end -0.67945 0.3048)
			(stroke
				(width 0.1)
				(type default)
			)
			(layer "F.Fab")
		)
		(fp_line
			(start 0.120396 0.2794)
			(end -0.12065 0.2794)
			(stroke
				(width 0.1)
				(type default)
			)
			(layer "F.Fab")
		)
		(fp_line
			(start 0.120396 0.3048)
			(end 0.120396 0.2794)
			(stroke
				(width 0.1)
				(type default)
			)
			(layer "F.Fab")
		)
		(fp_line
			(start 0.12065 -0.3048)
			(end 0.67945 -0.3048)
			(stroke
				(width 0.1)
				(type default)
			)
			(layer "F.Fab")
		)
		(fp_line
			(start 0.12065 -0.2794)
			(end 0.12065 -0.3048)
			(stroke
				(width 0.1)
				(type default)
			)
			(layer "F.Fab")
		)
		(fp_line
			(start 0.67945 -0.3048)
			(end 0.67945 0.3048)
			(stroke
				(width 0.1)
				(type default)
			)
			(layer "F.Fab")
		)
		(fp_line
			(start 0.67945 0.3048)
			(end 0.120396 0.3048)
			(stroke
				(width 0.1)
				(type default)
			)
			(layer "F.Fab")
		)
		(pad "1" smd circle
			(at -0.40005 0)
			(size 0 0)
			(layers "F.Cu" "F.Mask" "F.Paste")
			(net "P3V3_AUX")
		)
		(pad "2" smd circle
			(at 0.40005 0)
			(size 0 0)
			(layers "F.Cu" "F.Mask" "F.Paste")
			(net "PCA9548_PCIE3_ADDR0")
		)
	)
	(footprint ""
		(layer "F.Cu")
		(at 124.33808 -106.238548 -90)
		(property "Reference" "R4048"
			(at 0 0 270)
			(layer "F.SilkS")
			(hide yes)
			(effects
				(font
					(size 1.27 1.27)
				)
			)
		)
		(property "Value" ""
			(at 0 0 270)
			(layer "F.Fab")
			(effects
				(font
					(size 1.27 1.27)
				)
			)
		)
		(duplicate_pad_numbers_are_jumpers no)
		(fp_line
			(start -0.7874 0.4064)
			(end -0.7874 -0.4064)
			(stroke
				(width 0.1524)
				(type default)
			)
			(layer "F.SilkS")
		)
		(fp_line
			(start 0.7874 0.4064)
			(end -0.7874 0.4064)
			(stroke
				(width 0.1524)
				(type default)
			)
			(layer "F.SilkS")
		)
		(fp_line
			(start -0.7874 -0.4064)
			(end 0.7874 -0.4064)
			(stroke
				(width 0.1524)
				(type default)
			)
			(layer "F.SilkS")
		)
		(fp_line
			(start 0.7874 -0.4064)
			(end 0.7874 0.4064)
			(stroke
				(width 0.1524)
				(type default)
			)
			(layer "F.SilkS")
		)
		(fp_line
			(start -0.67945 0.3048)
			(end -0.67945 -0.305054)
			(stroke
				(width 0.1)
				(type default)
			)
			(layer "F.Fab")
		)
		(fp_line
			(start -0.12065 0.3048)
			(end -0.67945 0.3048)
			(stroke
				(width 0.1)
				(type default)
			)
			(layer "F.Fab")
		)
		(fp_line
			(start 0.120396 0.3048)
			(end 0.120396 0.2794)
			(stroke
				(width 0.1)
				(type default)
			)
			(layer "F.Fab")
		)
		(fp_line
			(start 0.67945 0.3048)
			(end 0.120396 0.3048)
			(stroke
				(width 0.1)
				(type default)
			)
			(layer "F.Fab")
		)
		(fp_line
			(start -0.12065 0.2794)
			(end -0.12065 0.3048)
			(stroke
				(width 0.1)
				(type default)
			)
			(layer "F.Fab")
		)
		(fp_line
			(start 0.120396 0.2794)
			(end -0.12065 0.2794)
			(stroke
				(width 0.1)
				(type default)
			)
			(layer "F.Fab")
		)
		(fp_line
			(start -0.12065 -0.2794)
			(end 0.12065 -0.2794)
			(stroke
				(width 0.1)
				(type default)
			)
			(layer "F.Fab")
		)
		(fp_line
			(start 0.12065 -0.2794)
			(end 0.12065 -0.3048)
			(stroke
				(width 0.1)
				(type default)
			)
			(layer "F.Fab")
		)
		(fp_line
			(start 0.12065 -0.3048)
			(end 0.67945 -0.3048)
			(stroke
				(width 0.1)
				(type default)
			)
			(layer "F.Fab")
		)
		(fp_line
			(start 0.67945 -0.3048)
			(end 0.67945 0.3048)
			(stroke
				(width 0.1)
				(type default)
			)
			(layer "F.Fab")
		)
		(fp_line
			(start -0.67945 -0.305054)
			(end -0.12065 -0.305054)
			(stroke
				(width 0.1)
				(type default)
			)
			(layer "F.Fab")
		)
		(fp_line
			(start -0.12065 -0.305054)
			(end -0.12065 -0.2794)
			(stroke
				(width 0.1)
				(type default)
			)
			(layer "F.Fab")
		)
		(pad "1" smd circle
			(at -0.40005 0 270)
			(size 0 0)
			(layers "F.Cu" "F.Mask" "F.Paste")
			(net "RST_CPU1_DRAM_EF_PLD_LVT3_R_N")
		)
		(pad "2" smd circle
			(at 0.40005 0 270)
			(size 0 0)
			(layers "F.Cu" "F.Mask" "F.Paste")
			(net "RST_CPU1_DRAM_EF_PLD_LVT3_N")
		)
	)
)
